# T6G (Grand Teton) — schematic netlist excerpt (pin names and nets, part order shuffled) for the footprints in the layout excerpt that follows; sources: Cadence DE-HDL packaged netlist, KiCad conversion of 04192023_DAF0TMB3IC0_F0TG_MB_C_brd_V02_OCP.brd

PL69  Q_INDUCTOR4P_14  150NH IND  pkg L_TLM117513Q-151QL_11X7-5XA  page 220
  \1\  = SW_PVDDCR_CPU1_P1_SW6
  \2\  = IND_CPU1_P1_CPL0
  \3\  = IND_CPU1_P1_CPL6
  \4\  = PVDDCR_CPU1_P1

R985  Q_RES  4.7K 5% EMPTY  pkg 0201LF  page 276 : A = P1V8_CPU0_RT_1D ; B = TEST2_RT_CPU0_P0
PC278  Q_CAP  0.1UF 25V 10% X7R  pkg 0402  page 211 : A = PVDDCR_CPU0_P1 ; B = GND

(kicad_pcb
	(version 20260206)
	(generator "pcbnew")
	(generator_version "10.0")
	(general
		(thickness 1.6)
		(legacy_teardrops no)
	)
	(paper "A4")
	(title_block
		(title "04192023_DAF0TMB3IC0_F0TG_MB_C_brd_V02_OCP.brd")
		(comment 1 "Grand Teton / footprints 2435-2437 of 8354")
	)
	(layers
		(0 "F.Cu" signal "TOP")
		(4 "In1.Cu" signal "GND")
		(6 "In2.Cu" signal "IN1")
		(8 "In3.Cu" signal "GND1")
		(10 "In4.Cu" signal "IN2")
		(12 "In5.Cu" signal "GND2")
		(14 "In6.Cu" signal "IN3")
		(16 "In7.Cu" signal "GND3")
		(18 "In8.Cu" signal "VCC")
		(20 "In9.Cu" signal "VCC1")
		(22 "In10.Cu" signal "GND4")
		(24 "In11.Cu" signal "IN4")
		(26 "In12.Cu" signal "GND5")
		(28 "In13.Cu" signal "IN5")
		(30 "In14.Cu" signal "GND6")
		(32 "In15.Cu" signal "IN6")
		(34 "In16.Cu" signal "GND7")
		(2 "B.Cu" signal "BOTTOM")
		(9 "F.Adhes" user "F.Adhesive")
		(11 "B.Adhes" user "B.Adhesive")
		(13 "F.Paste" user "Package Geometry/Pastemask Top")
		(15 "B.Paste" user "Package Geometry/Pastemask Bottom")
		(5 "F.SilkS" user "Ref Des/Silkscreen Top")
		(7 "B.SilkS" user "Ref Des/Silkscreen Bottom")
		(1 "F.Mask" user "Board Geometry/Soldermask Top")
		(3 "B.Mask" user "Board Geometry/Soldermask Bottom")
		(17 "Dwgs.User" user "User.Drawings")
		(19 "Cmts.User" user "User.Comments")
		(21 "Eco1.User" user "User.Eco1")
		(23 "Eco2.User" user "User.Eco2")
		(25 "Edge.Cuts" user "Board Geometry/Outline")
		(27 "Margin" user)
		(31 "F.CrtYd" user "Package Geometry/Place Bound Top")
		(29 "B.CrtYd" user "Package Geometry/Place Bound Bottom")
		(35 "F.Fab" user "Ref Des/Assembly Top")
		(33 "B.Fab" user "Ref Des/Assembly Bottom")
	)
	(footprint ""
		(layer "F.Cu")
		(at 103.847138 -330.622148)
		(property "Reference" "PL69"
			(at -3.115056 -15.887446 0)
			(unlocked yes)
			(layer "F.SilkS")
			(effects
				(font
					(size 0.7874 0.5842)
					(thickness 0.1524)
				)
				(justify left)
			)
		)
		(property "Value" ""
			(at 0 0 0)
			(layer "F.Fab")
			(effects
				(font
					(size 1.27 1.27)
				)
			)
		)
		(duplicate_pad_numbers_are_jumpers no)
		(fp_line
			(start -3.750056 -5.500116)
			(end -2.393442 -5.500116)
			(stroke
				(width 0.1524)
				(type default)
			)
			(layer "F.SilkS")
		)
		(fp_line
			(start -3.750056 5.500116)
			(end -3.750056 -5.500116)
			(stroke
				(width 0.1524)
				(type default)
			)
			(layer "F.SilkS")
		)
		(fp_line
			(start -2.393442 5.500116)
			(end -3.750056 5.500116)
			(stroke
				(width 0.1524)
				(type default)
			)
			(layer "F.SilkS")
		)
		(fp_line
			(start 2.393442 5.500116)
			(end 3.750056 5.500116)
			(stroke
				(width 0.1524)
				(type default)
			)
			(layer "F.SilkS")
		)
		(fp_line
			(start 3.750056 -5.500116)
			(end 2.393442 -5.500116)
			(stroke
				(width 0.1524)
				(type default)
			)
			(layer "F.SilkS")
		)
		(fp_line
			(start 3.750056 5.500116)
			(end 3.750056 -5.500116)
			(stroke
				(width 0.1524)
				(type default)
			)
			(layer "F.SilkS")
		)
		(fp_poly
			(pts
				(xy -3.847084 -5.385308) (xy -4.305046 -5.537962) (xy -3.999738 -5.84327)
			)
			(stroke
				(width 0)
				(type default)
			)
			(fill yes)
			(layer "F.SilkS")
		)
		(fp_line
			(start -3.750056 -5.500116)
			(end -3.750056 5.500116)
			(stroke
				(width 0.1)
				(type default)
			)
			(layer "F.Fab")
		)
		(fp_line
			(start -3.750056 5.500116)
			(end 3.750056 5.500116)
			(stroke
				(width 0.1)
				(type default)
			)
			(layer "F.Fab")
		)
		(fp_line
			(start 3.750056 -5.500116)
			(end -3.750056 -5.500116)
			(stroke
				(width 0.1)
				(type default)
			)
			(layer "F.Fab")
		)
		(fp_line
			(start 3.750056 5.500116)
			(end 3.750056 -5.500116)
			(stroke
				(width 0.1)
				(type default)
			)
			(layer "F.Fab")
		)
		(fp_poly
			(pts
				(xy -4.9276 -4.757928) (xy -4.9276 -3.741928) (xy -3.9116 -4.249928)
			)
			(stroke
				(width 0)
				(type default)
			)
			(fill yes)
			(layer "F.Fab")
		)
		(pad "1" smd rect
			(at 0 -4.249928 270)
			(size 2.413 4.5212)
			(layers "F.Cu" "F.Mask" "F.Paste")
			(net "SW_PVDDCR_CPU1_P1_SW6")
		)
		(pad "2" smd rect
			(at 0 -1.175004 270)
			(size 1.3716 4.5212)
			(layers "F.Cu" "F.Mask" "F.Paste")
			(net "IND_CPU1_P1_CPL0")
		)
		(pad "3" smd rect
			(at 0 1.175004 270)
			(size 1.3716 4.5212)
			(layers "F.Cu" "F.Mask" "F.Paste")
			(net "IND_CPU1_P1_CPL6")
		)
		(pad "4" smd rect
			(at 0 4.249928 270)
			(size 2.413 4.5212)
			(layers "F.Cu" "F.Mask" "F.Paste")
			(net "PVDDCR_CPU1_P1")
		)
	)
	(footprint ""
		(layer "F.Cu")
		(at 297.741594 -392.1252)
		(property "Reference" "R985"
			(at 0 0 0)
			(layer "F.SilkS")
			(hide yes)
			(effects
				(font
					(size 1.27 1.27)
				)
			)
		)
		(property "Value" ""
			(at 0 0 0)
			(layer "F.Fab")
			(effects
				(font
					(size 1.27 1.27)
				)
			)
		)
		(duplicate_pad_numbers_are_jumpers no)
		(fp_line
			(start -0.32512 -0.175006)
			(end 0.32512 -0.175006)
			(stroke
				(width 0.1)
				(type default)
			)
			(layer "F.Fab")
		)
		(fp_line
			(start -0.32512 0.175006)
			(end -0.32512 -0.175006)
			(stroke
				(width 0.1)
				(type default)
			)
			(layer "F.Fab")
		)
		(fp_line
			(start 0.32512 -0.175006)
			(end 0.32512 0.175006)
			(stroke
				(width 0.1)
				(type default)
			)
			(layer "F.Fab")
		)
		(fp_line
			(start 0.32512 0.175006)
			(end -0.32512 0.175006)
			(stroke
				(width 0.1)
				(type default)
			)
			(layer "F.Fab")
		)
		(pad "1" smd rect
			(at -0.2667 0)
			(size 0.3048 0.381)
			(layers "F.Cu" "F.Mask" "F.Paste")
			(net "P1V8_CPU0_RT_1D")
		)
		(pad "2" smd rect
			(at 0.2667 0 180)
			(size 0.3048 0.381)
			(layers "F.Cu" "F.Mask" "F.Paste")
			(net "TEST2_RT_CPU0_P0")
		)
	)
	(footprint ""
		(layer "F.Cu")
		(at 60.920122 -181.291992 -90)
		(property "Reference" "PC278"
			(at 0 0 270)
			(layer "F.SilkS")
			(hide yes)
			(effects
				(font
					(size 1.27 1.27)
				)
			)
		)
		(property "Value" ""
			(at 0 0 270)
			(layer "F.Fab")
			(effects
				(font
					(size 1.27 1.27)
				)
			)
		)
		(duplicate_pad_numbers_are_jumpers no)
		(fp_line
			(start -0.7874 0.4064)
			(end -0.7874 -0.4064)
			(stroke
				(width 0.1524)
				(type default)
			)
			(layer "F.SilkS")
		)
		(fp_line
			(start 0.7874 0.4064)
			(end -0.7874 0.4064)
			(stroke
				(width 0.1524)
				(type default)
			)
			(layer "F.SilkS")
		)
		(fp_line
			(start -0.7874 -0.4064)
			(end 0.7874 -0.4064)
			(stroke
				(width 0.1524)
				(type default)
			)
			(layer "F.SilkS")
		)
		(fp_line
			(start 0.7874 -0.4064)
			(end 0.7874 0.4064)
			(stroke
				(width 0.1524)
				(type default)
			)
			(layer "F.SilkS")
		)
		(fp_line
			(start -0.67945 0.3048)
			(end -0.67945 -0.305054)
			(stroke
				(width 0.1)
				(type default)
			)
			(layer "F.Fab")
		)
		(fp_line
			(start -0.12065 0.3048)
			(end -0.67945 0.3048)
			(stroke
				(width 0.1)
				(type default)
			)
			(layer "F.Fab")
		)
		(fp_line
			(start 0.120396 0.3048)
			(end 0.120396 0.2794)
			(stroke
				(width 0.1)
				(type default)
			)
			(layer "F.Fab")
		)
		(fp_line
			(start 0.67945 0.3048)
			(end 0.120396 0.3048)
			(stroke
				(width 0.1)
				(type default)
			)
			(layer "F.Fab")
		)
		(fp_line
			(start -0.12065 0.2794)
			(end -0.12065 0.3048)
			(stroke
				(width 0.1)
				(type default)
			)
			(layer "F.Fab")
		)
		(fp_line
			(start 0.120396 0.2794)
			(end -0.12065 0.2794)
			(stroke
				(width 0.1)
				(type default)
			)
			(layer "F.Fab")
		)
		(fp_line
			(start -0.12065 -0.2794)
			(end 0.12065 -0.2794)
			(stroke
				(width 0.1)
				(type default)
			)
			(layer "F.Fab")
		)
		(fp_line
			(start 0.12065 -0.2794)
			(end 0.12065 -0.3048)
			(stroke
				(width 0.1)
				(type default)
			)
			(layer "F.Fab")
		)
		(fp_line
			(start 0.12065 -0.3048)
			(end 0.67945 -0.3048)
			(stroke
				(width 0.1)
				(type default)
			)
			(layer "F.Fab")
		)
		(fp_line
			(start 0.67945 -0.3048)
			(end 0.67945 0.3048)
			(stroke
				(width 0.1)
				(type default)
			)
			(layer "F.Fab")
		)
		(fp_line
			(start -0.67945 -0.305054)
			(end -0.12065 -0.305054)
			(stroke
				(width 0.1)
				(type default)
			)
			(layer "F.Fab")
		)
		(fp_line
			(start -0.12065 -0.305054)
			(end -0.12065 -0.2794)
			(stroke
				(width 0.1)
				(type default)
			)
			(layer "F.Fab")
		)
		(pad "1" smd circle
			(at -0.40005 0 270)
			(size 0 0)
			(layers "F.Cu" "F.Mask" "F.Paste")
			(net "PVDDCR_CPU0_P1")
		)
		(pad "2" smd circle
			(at 0.40005 0 270)
			(size 0 0)
			(layers "F.Cu" "F.Mask" "F.Paste")
			(net "GND")
		)
	)
)
